FILE_TYPE=PINLIST;
{ Packager-XL run on 05-Sep-2022 AT 15:23:30 }
TIME=' COMPILATION ON 05-Sep-2022 AT 15:23:30';
primitive '24LC16BT_I_ST_TSSOP8-G221-1017A';body '24LC16BT_I_ST_TSSOP8';
    'A0':'(1,0)';$S;BIDI;
    'A1':'(2,0)';$S;BIDI;
    'A2':'(3,0)';$S;BIDI;
    'WP':'(7,0)';$S;IN;
    'SCL':'(6,0)';$S;IN;
    'SDA':'(5,0)';$S;BIDI;
    'VSS':'(0,4)';$S;
    'VCC':'(0,8)';$S;
end_primitive;
primitive '74HCT2G125DP_TSSOP8-G220-00055A';body '74HCT2G125DP_TSSOP8';
    '1OE*':'(1)';BIDI;
    '1A':'(2)';IN;
    '2Y':'(3)';OUT;
    'GND':'(4)';
    '2A':'(5)';IN;
    '1Y':'(6)';OUT;
    '2OE*':'(7)';BIDI;
    'VCC':'(8)';
end_primitive;
primitive '74LVC1G07_SC70_5-G220-10017-01';body '74LVC1G07_SC70_5';
    'A':'(2,0)';$S;IN;
    'NC':'(1,0)';$S;
    'Y':'(4,0)';$S;OUT;
    'GND':'(0,3)';$S;
    'VCC':'(0,5)';$S;
end_primitive;
primitive 'AT24MAC402_SOT23_5-A221-00002-A';body 'AT24MAC402_SOT23_5';
    'SCL':'(1)';BIDI;
    'GND':'(2)';
    'SDA':'(3)';BIDI;
    'VCC':'(4)';
    'WP':'(5)';BIDI;
end_primitive;
primitive 'BNO080_LGA_28-A246-00002-FB,BNA';body 'BNO080_LGA_28';
    'BOOTN':'(4)';IN;
    'CAP':'(9)';BIDI;
    'CLKSEL0':'(10)';IN;
    'ENV_SCL':'(15)';BIDI;
    'ENV_SDA':'(16)';BIDI;
    'GND_1':'(2)';
    'GND_2':'(25)';
    'H_CS*':'(18)';IN;
    'H_INTN':'(14)';OUT;
    'H_SCL/SCK/RX':'(19)';BIDI;
    'H_SDA/H_MISO/TX':'(20)';BIDI;
    'RST*':'(11)';IN;
    'PS0/WAKE':'(6)';IN;
    'PS1':'(5)';IN;
    'RESV_NC_1':'(1)';
    'RESV_NC_2':'(7)';IN;
    'RESV_NC_3':'(8)';
    'RESV_NC_4':'(12)';
    'RESV_NC_5':'(13)';
    'RESV_NC_6':'(21)';
    'RESV_NC_7':'(22)';
    'RESV_NC_8':'(23)';
    'RESV_NC_9':'(24)';
    'SA0/H_MOSI':'(17)';IN;
    'VDD':'(3)';IN;
    'VDDIO':'(28)';IN;
    'XIN32':'(27)';IN;
    'XOUT32/CLKSEL1':'(26)';OUT;
end_primitive;
primitive 'CAPACITOR-G104-0A120-FJ,12PF,5%';body 'CAPACITOR';
    '1':'(1)';
    '2':'(2)';
end_primitive;
primitive 'CAPACITOR-G104-0A180-FJ,18PF,5%';body 'CAPACITOR';
    '1':'(1)';
    '2':'(2)';
end_primitive;
primitive 'CAPACITOR-G104-0B101-FK,100PF,A';body 'CAPACITOR';
    '1':'(1)';
    '2':'(2)';
end_primitive;
primitive 'CAPACITOR-G104-0B103-EK,0.01UFA';body 'CAPACITOR';
    '1':'(1)';
    '2':'(2)';
end_primitive;
primitive 'CAPACITOR-G104-0B472-EK,4700PFA';body 'CAPACITOR';
    '1':'(1)';
    '2':'(2)';
end_primitive;
primitive 'CAPACITOR-G104-0F224-BK,0.22UFA';body 'CAPACITOR';
    '1':'(1)';
    '2':'(2)';
end_primitive;
primitive 'CAPACITOR-G105-0A102-FJ,1000PFA';body 'CAPACITOR';
    '1':'(1)';
    '2':'(2)';
end_primitive;
primitive 'CAPACITOR-G105-0B104-CK,0.1UF,A';body 'CAPACITOR';
    '1':'(1)';
    '2':'(2)';
end_primitive;
primitive 'CAPACITOR-G105-0B104-EK,0.1UF,A';body 'CAPACITOR';
    '1':'(1)';
    '2':'(2)';
end_primitive;
primitive 'CAPACITOR-G105-0B222-FK,2200PFA';body 'CAPACITOR';
    '1':'(1)';
    '2':'(2)';
end_primitive;
primitive 'CAPACITOR-G105-0B223-EK,0.022UA';body 'CAPACITOR';
    '1':'(1)';
    '2':'(2)';
end_primitive;
primitive 'CAPACITOR-G105-0B224-DK,0.22UFA';body 'CAPACITOR';
    '1':'(1)';
    '2':'(2)';
end_primitive;
primitive 'CAPACITOR-G105-0C106-BM,10UF,2A';body 'CAPACITOR';
    '1':'(1)';
    '2':'(2)';
end_primitive;
primitive 'CAPACITOR-G105-0F475-BM,4.7UF,A';body 'CAPACITOR';
    '1':'(1)';
    '2':'(2)';
end_primitive;
primitive 'CAPACITOR-G107-0F106-EM,10UF,2A';body 'CAPACITOR';
    '1':'(1)';
    '2':'(2)';
end_primitive;
primitive 'CAPACITOR-G107-0F226-CM,22UF,2A';body 'CAPACITOR';
    '1':'(1)';
    '2':'(2)';
end_primitive;
primitive 'CAPACITOR-G107-0F476-AM,47UF,2A';body 'CAPACITOR';
    '1':'(1)';
    '2':'(2)';
end_primitive;
primitive 'CAPACITOR-G109-0G107-BM,100UF,A';body 'CAPACITOR';
    '1':'(1)';
    '2':'(2)';
end_primitive;
primitive 'CAT93C46VI_GT3_SOIC8-G221-1007A';body 'CAT93C46VI_GT3_SOIC8';
    'CS':'(1,0)';$S;BIDI;
    'SK':'(2,0)';$S;IN;
    'DI':'(3,0)';$S;IN;
    'DO':'(4,0)';$S;OUT;
    'ORG':'(6,0)';$S;BIDI;
    'NC':'(7,0)';$S;
    'VCC':'(0,8)';$S;
    'GND':'(0,5)';$S;
end_primitive;
primitive 'CL1001485A-G122-00019-01';body 'CL1001485A';
    '1':'(1)';BIDI;
    '2':'(2)';BIDI;
    '3':'(3)';BIDI;
    '4':'(4)';BIDI;
    '5':'(5)';BIDI;
    '6':'(6)';BIDI;
end_primitive;
primitive 'CL5003148A-G220-10019-01';body 'CL5003148A';
    'A':'(1,0)';$S;IN;
    'B':'(2,0)';$S;IN;
    'Y':'(4,0)';$S;OUT;
    'GND':'(0,3)';$S;
    'VCC':'(0,5)';$S;
end_primitive;
primitive 'CONN_64P_GF-S_M_EF64_PCIE_P039A';body 'CONN_64P_GF';
    'P_12V1':'(B1)';
    'P_12V2':'(B2)';
    'P_12V4':'(B3)';
    'GND1':'(B4)';
    'SMCLK':'(B5)';BIDI;
    'SMDAT':'(B6)';BIDI;
    'GND3':'(B7)';
    'P_3V3_1':'(B8)';
    'JTAG1':'(B9)';BIDI;
    'P_3V3AUX':'(B10)';
    'WAKE*':'(B11)';BIDI;
    'RSVD1':'(B12)';BIDI;
    'GND5':'(B13)';
    'PETP0':'(B14)';BIDI;
    'PETN0':'(B15)';BIDI;
    'GND7':'(B16)';
    'PRSNT2_1*':'(B17)';BIDI;
    'GND9':'(B18)';
    'PETP1':'(B19)';BIDI;
    'PETN1':'(B20)';BIDI;
    'GND11':'(B21)';
    'GND12':'(B22)';
    'PETP2':'(B23)';BIDI;
    'PETN2':'(B24)';BIDI;
    'GND15':'(B25)';
    'GND17':'(B26)';
    'PETP3':'(B27)';BIDI;
    'PETN3':'(B28)';BIDI;
    'GND20':'(B29)';
    'RSVD3':'(B30)';BIDI;
    'PRSNT2_2*':'(B31)';BIDI;
    'GND22':'(B32)';
    'PRSNT1*':'(A1)';BIDI;
    'P_12V3':'(A2)';
    'P_12V5':'(A3)';
    'GND2':'(A4)';
    'JTAG2':'(A5)';BIDI;
    'JTAG3':'(A6)';BIDI;
    'JTAG4':'(A7)';BIDI;
    'JTAG5':'(A8)';BIDI;
    'P_3V3_2':'(A9)';
    'P_3V3_3':'(A10)';
    'PERST*':'(A11)';BIDI;
    'GND4':'(A12)';
    'REFCLK_P':'(A13)';BIDI;
    'REFCLK_N':'(A14)';BIDI;
    'GND6':'(A15)';
    'PERP0':'(A16)';BIDI;
    'PERN0':'(A17)';BIDI;
    'GND8':'(A18)';
    'RSVD2':'(A19)';BIDI;
    'GND10':'(A20)';
    'PERP1':'(A21)';BIDI;
    'PERN1':'(A22)';BIDI;
    'GND13':'(A23)';
    'GND14':'(A24)';
    'PERP2':'(A25)';BIDI;
    'PERN2':'(A26)';BIDI;
    'GND18':'(A27)';
    'GND19':'(A28)';
    'PERP3':'(A29)';BIDI;
    'PERN3':'(A30)';BIDI;
    'GND21':'(A31)';
    'RSVD4':'(A32)';BIDI;
end_primitive;
primitive 'CONN_HDR_1X3_M_S_SMT-G205-1002A';body 'CONN_HDR_1X3_M_S_SMT';
    '1':'(1)';BIDI;
    '2':'(2)';BIDI;
    '3':'(3)';BIDI;
end_primitive;
primitive 'CONN_HDR_2X10_M_S_SMT-G200-130A';body 'CONN_HDR_2X10_M_S_SMT';
    '1':'(1)';BIDI;
    '3':'(3)';BIDI;
    '5':'(5)';BIDI;
    '7':'(7)';BIDI;
    '9':'(9)';BIDI;
    '11':'(11)';BIDI;
    '13':'(13)';BIDI;
    '15':'(15)';BIDI;
    '17':'(17)';BIDI;
    '19':'(19)';BIDI;
    '2':'(2)';BIDI;
    '4':'(4)';BIDI;
    '6':'(6)';BIDI;
    '8':'(8)';BIDI;
    '10':'(10)';BIDI;
    '12':'(12)';BIDI;
    '14':'(14)';BIDI;
    '16':'(16)';BIDI;
    '18':'(18)';BIDI;
    '20':'(20)';BIDI;
end_primitive;
primitive 'CONN_HDR_2X2_M_S_SMT-G200-1068A';body 'CONN_HDR_2X2_M_S_SMT';
    '1':'(1)';BIDI;
    '2':'(2)';BIDI;
    '3':'(3)';BIDI;
    '4':'(4)';BIDI;
end_primitive;
primitive 'CONN_HDR_2X3_M_RA_TH-G200-1251A';body 'CONN_HDR_2X3_M_RA_TH';
    '1':'(1)';BIDI;
    '2':'(2)';BIDI;
    '3':'(3)';BIDI;
    '4':'(4)';BIDI;
    '5':'(5)';BIDI;
    '6':'(6)';BIDI;
end_primitive;
primitive 'CONN_HDR_2X4_F_S_SMT-G200-1307A';body 'CONN_HDR_2X4_F_S_SMT';
    '1':'(1)';BIDI;
    '2':'(2)';BIDI;
    '3':'(3)';BIDI;
    '4':'(4)';BIDI;
    '5':'(5)';BIDI;
    '6':'(6)';BIDI;
    '7':'(7)';BIDI;
    '8':'(8)';BIDI;
end_primitive;
primitive 'CONN_HDR_2X6_F_S_SMT-G200-1313A';body 'CONN_HDR_2X6_F_S_SMT';
    '1':'(1)';BIDI;
    '3':'(3)';BIDI;
    '5':'(5)';BIDI;
    '7':'(7)';BIDI;
    '9':'(9)';BIDI;
    '11':'(11)';BIDI;
    '2':'(2)';BIDI;
    '4':'(4)';BIDI;
    '6':'(6)';BIDI;
    '8':'(8)';BIDI;
    '10':'(10)';BIDI;
    '12':'(12)';BIDI;
end_primitive;
primitive 'CONN_JACK_1P_GH4_S_TH-G200-130A';body 'CONN_JACK_1P_GH4_S_TH';
    '1':'(1)';BIDI;
    'GH1':'(GH1)';BIDI;
    'GH2':'(GH2)';BIDI;
    'GH3':'(GH3)';BIDI;
    'GH4':'(GH4)';BIDI;
end_primitive;
primitive 'CONN_USB_14P_GH4_F_RA_TH-G200-A';body 'CONN_USB_14P_GH4_F_RA_TH';
    'GND_1':'(A1)';
    'VBUS_1':'(A4)';
    'CC1':'(A5)';BIDI;
    'D1_P':'(A6)';BIDI;
    'D1_N':'(A7)';BIDI;
    'VBUS_2':'(A9)';
    'GND_2':'(A12)';
    'GND_3':'(B1)';
    'VBUS_3':'(B4)';
    'CC2':'(B5)';BIDI;
    'D2_P':'(B6)';BIDI;
    'D2_N':'(B7)';BIDI;
    'VBUS_4':'(B9)';
    'GND_4':'(B12)';
    'GH1':'(GH1)';
    'GH2':'(GH2)';
    'GH3':'(GH3)';
    'GH4':'(GH4)';
end_primitive;
primitive 'CONN_USB_1X5_G2_GH4_F_RA_SMT-GA';body 'CONN_USB_1X5_G2_GH4_F_RA_SMT';
    '1':'(1)';BIDI;
    '2':'(2)';BIDI;
    '3':'(3)';BIDI;
    '4':'(4)';BIDI;
    '5':'(5)';BIDI;
    'G1':'(G1)';
    'G2':'(G2)';
    'GH1':'(GH1)';BIDI;
    'GH2':'(GH2)';BIDI;
    'GH3':'(GH3)';BIDI;
    'GH4':'(GH4)';BIDI;
end_primitive;
primitive 'DIODE_2-G122-00005-01';body 'DIODE_2';
    'C':'(C)';BIDI;
    'A':'(A)';BIDI;
end_primitive;
primitive 'DIODE_2E-G122-10190-01';body 'DIODE_2E';
    'C':'(C)';BIDI;
    'A':'(A)';BIDI;
end_primitive;
primitive 'DIODE_2F-G122-10186-01';body 'DIODE_2F';
    'C':'(C)';BIDI;
    'A':'(A)';BIDI;
end_primitive;
primitive 'DIODE_3F-G122-10080-01';body 'DIODE_3F';
    'A_1':'(1)';BIDI;
    'A_2':'(2)';BIDI;
    'C':'(3)';BIDI;
end_primitive;
primitive 'DIODE_4_V1-G122-10123-01';body 'DIODE_4_V1';
    'GND':'(1)';
    'IO1':'(2)';BIDI;
    'IO2':'(3)';BIDI;
    'VDD':'(4)';
end_primitive;
primitive 'FERRITEBEAD-G191-10097-01,600OA';body 'FERRITEBEAD';
    '1':'(1)';
    '2':'(2)';
end_primitive;
primitive 'FERRITEBEAD-G191-10100-01,120OA';body 'FERRITEBEAD';
    '1':'(1)';
    '2':'(2)';
end_primitive;
primitive 'FERRITEBEAD-G191-10101-01,26OHA';body 'FERRITEBEAD';
    '1':'(1)';
    '2':'(2)';
end_primitive;
primitive 'FT4232HL_REEL_QFP64-G223-10282A';body 'FT4232HL_REEL_QFP64';
    'ADBUS0':'(16)';BIDI;
    'ADBUS1':'(17)';BIDI;
    'ADBUS2':'(18)';BIDI;
    'ADBUS3':'(19)';BIDI;
    'ADBUS4':'(21)';BIDI;
    'ADBUS5':'(22)';BIDI;
    'ADBUS6':'(23)';BIDI;
    'ADBUS7':'(24)';BIDI;
    'BDBUS0':'(26)';BIDI;
    'BDBUS1':'(27)';BIDI;
    'BDBUS2':'(28)';BIDI;
    'BDBUS3':'(29)';BIDI;
    'BDBUS4':'(30)';BIDI;
    'BDBUS5':'(32)';BIDI;
    'BDBUS6':'(33)';BIDI;
    'BDBUS7':'(34)';BIDI;
    'CDBUS0':'(38)';BIDI;
    'CDBUS1':'(39)';BIDI;
    'CDBUS2':'(40)';BIDI;
    'CDBUS3':'(41)';BIDI;
    'CDBUS4':'(43)';BIDI;
    'CDBUS5':'(44)';BIDI;
    'CDBUS6':'(45)';BIDI;
    'CDBUS7':'(46)';BIDI;
    'DDBUS0':'(48)';BIDI;
    'DDBUS1':'(52)';BIDI;
    'DDBUS2':'(53)';BIDI;
    'DDBUS3':'(54)';BIDI;
    'DDBUS4':'(55)';BIDI;
    'DDBUS5':'(57)';BIDI;
    'DDBUS6':'(58)';BIDI;
    'DDBUS7':'(59)';BIDI;
    'PWREN*':'(60)';BIDI;
    'SUSPEND*':'(36)';BIDI;
    'VREGIN':'(50)';IN;
    'VREGOUT':'(49)';OUT;
    'VCCIO_1':'(56)';
    'VCCIO_2':'(42)';
    'VCCIO_3':'(31)';
    'VCCIO_4':'(20)';
    'VCORE_1':'(64)';
    'VCORE_2':'(37)';
    'VCORE_3':'(12)';
    'VPLL':'(9)';BIDI;
    'VPHY':'(4)';BIDI;
    'AGND':'(10)';
    'GND_1':'(51)';
    'GND_2':'(47)';
    'GND_3':'(35)';
    'GND_4':'(25)';
    'GND_5':'(15)';
    'GND_6':'(11)';
    'GND_7':'(5)';
    'GND_8':'(1)';
    'DM':'(7)';BIDI;
    'DP':'(8)';BIDI;
    'REF':'(6)';IN;
    'RESET*':'(14)';BIDI;
    'EECS':'(63)';BIDI;
    'EECLK':'(62)';BIDI;
    'EEDATA':'(61)';BIDI;
    'OSCI':'(2)';BIDI;
    'OSCO':'(3)';BIDI;
    'TEST':'(13)';BIDI;
end_primitive;
primitive 'FUSE-G280-10012-01,2.5A';body 'FUSE';
    '1':'(1)';BIDI;
    '2':'(2)';BIDI;
end_primitive;
primitive 'FUSE-G280-10049-01,1A';body 'FUSE';
    '1':'(1)';BIDI;
    '2':'(2)';BIDI;
end_primitive;
primitive 'G200_10283_01-G200-10283-01';body 'G200_10283_01';
    '1':'(1)';BIDI;
    '2':'(2)';BIDI;
    '3':'(3)';BIDI;
    '4':'(4)';BIDI;
    '5':'(5)';BIDI;
    '6':'(6)';BIDI;
    '7':'(7)';BIDI;
    '8':'(8)';BIDI;
    '9':'(9)';BIDI;
    '10':'(10)';BIDI;
end_primitive;
primitive 'G220_10198_01-G223-10197-01';body 'G220_10198_01';
    'EN':'(1)';BIDI;
    'SCLOUT':'(2)';OUT;
    'SCLIN':'(3)';IN;
    'GND':'(4)';
    'READY':'(5)';BIDI;
    'SDAIN':'(6)';IN;
    'SDAOUT':'(7)';OUT;
    'VCC':'(8)';
end_primitive;
primitive 'ICP_10100_LGA10-A222-00002-FB,A';body 'ICP_10100_LGA10';
    'RESV_1':'(1)';BIDI;
    'SCL':'(2)';BIDI;
    'RESV_2':'(3)';BIDI;
    'SDA':'(4)';BIDI;
    'RESV_3':'(5)';BIDI;
    'RESV_4':'(6)';BIDI;
    'RESV_5':'(7)';BIDI;
    'GND_1':'(8)';
    'GND_2':'(9)';
    'VDD':'(10)';
end_primitive;
primitive 'INDUCTOR_2-G190-10418-01,1.0UHA';body 'INDUCTOR_2';
    '1':'(1)';BIDI;
    '2':'(2)';BIDI;
end_primitive;
primitive 'INDUCTOR_2-G190-10424-01,4.7UHA';body 'INDUCTOR_2';
    '1':'(1)';BIDI;
    '2':'(2)';BIDI;
end_primitive;
primitive 'IS32FL3207_QWLA3_TR_QFN29-A223A';body 'IS32FL3207_QWLA3_TR_QFN29';
    'SDB*':'(1)';BIDI;
    'AD':'(2)';BIDI;
    'VCC':'(3)';
    'GND_1':'(4)';
    'ISET':'(5)';BIDI;
    'SDA':'(6)';BIDI;
    'SCL':'(7)';BIDI;
    'OUT1':'(8)';OUT;
    'OUT2':'(9)';OUT;
    'OUT3':'(10)';OUT;
    'GND_2':'(11)';
    'OUT4':'(12)';OUT;
    'OUT5':'(13)';OUT;
    'OUT6':'(14)';OUT;
    'OUT7':'(15)';OUT;
    'OUT8':'(16)';OUT;
    'OUT9':'(17)';OUT;
    'GND_3':'(18)';
    'OUT10':'(19)';OUT;
    'OUT11':'(20)';OUT;
    'OUT12':'(21)';OUT;
    'OUT13':'(22)';OUT;
    'OUT14':'(23)';OUT;
    'OUT15':'(24)';OUT;
    'GND_4':'(25)';
    'OUT16':'(26)';OUT;
    'OUT17':'(27)';OUT;
    'OUT18':'(28)';OUT;
    'THRM_PAD':'(29)';
end_primitive;
primitive 'ISL80101IRAJZ_DFN10-G222-10136A';body 'ISL80101IRAJZ_DFN10';
    'VOUT_1':'(1)';OUT;
    'VOUT_2':'(2)';OUT;
    'SENSE/ADJ':'(3)';BIDI;
    'PG':'(4)';BIDI;
    'GND':'(5)';
    'SS':'(6)';BIDI;
    'ENABLE':'(7)';BIDI;
    'NC':'(8)';
    'VIN_1':'(9)';IN;
    'VIN_2':'(10)';IN;
    'THRM_PAD':'(11)';
end_primitive;
primitive 'LED_4P_V14-G170-10189-01';body 'LED_4P_V14';
    '4':'(4)';BIDI;
    '3':'(3)';BIDI;
    '1':'(1)';BIDI;
    '2':'(2)';BIDI;
end_primitive;
primitive 'LM75BDP_TSSOP8-G220-10215-01';body 'LM75BDP_TSSOP8';
    'SDA':'(1,0)';$S;BIDI;
    'SCL':'(2,0)';$S;IN;
    'OS':'(3,0)';$S;OUT;
    'A2':'(5,0)';$S;IN;
    'A1':'(6,0)';$S;IN;
    'A0':'(7,0)';$S;IN;
    'VCC':'(0,8)';$S;
    'GND':'(0,4)';$S;
end_primitive;
primitive 'MEC_MTH8-MTH125C236N_V8-MTH125A';body 'MEC_MTH8';
    '2':'(2)';
    '3':'(3)';
    '1':'(1)';
    '4':'(4)';
    '6':'(6)';
    '5':'(5)';
    '7':'(7)';
    '8':'(8)';
end_primitive;
primitive 'MEC_NPTH-MTH100C240N-MTH100C24A';body 'MEC_NPTH';
end_primitive;
primitive 'MP5022CGQV_Z_QFN22-G220-10510-A';body 'MP5022CGQV_Z_QFN22';
    'EN':'(1)';IN;
    'LOADEN':'(2)';IN;
    'ENTM':'(3)';BIDI;
    'TIMER':'(4)';BIDI;
    'ISET':'(5)';BIDI;
    'SS':'(6)';BIDI;
    'GND':'(7)';
    'IMON':'(8)';OUT;
    'FLTB':'(9)';OUT;
    'PG':'(10)';OUT;
    'OV':'(11)';IN;
    'AVIN':'(12)';
    'VOUT_1':'(13)';OUT;
    'VOUT_2':'(14)';OUT;
    'VOUT_3':'(15)';OUT;
    'VOUT_4':'(16)';OUT;
    'VOUT_5':'(17)';OUT;
    'VOUT_6':'(18)';OUT;
    'VOUT_7':'(19)';OUT;
    'VOUT_8':'(20)';OUT;
    'VIN_1':'(21)';
    'VIN_2':'(22)';
    'VIN_3':'(23)';
    'VIN_4':'(24)';
    'VIN_5':'(25)';
    'VIN_6':'(26)';
end_primitive;
primitive 'MT25QL128ABA1ESE_SOP8-G221-102A';body 'MT25QL128ABA1ESE_SOP8';
    'S*':'(1)';IN;
    'DQ1':'(2)';BIDI;
    'W/DQ2*':'(3)';BIDI;
    'VSS':'(4)';
    'DQ0':'(5)';BIDI;
    'C':'(6)';IN;
    'HOLD/DQ3*':'(7)';BIDI;
    'VCC':'(8)';
end_primitive;
primitive 'NCP45560IMNTWG_H_DFN12-G222-10A';body 'NCP45560IMNTWG_H_DFN12';
    'VIN_1':'(1,0)';$S;BIDI;
    'EN':'(2,0)';$S;BIDI;
    'SR':'(5,0)';$S;BIDI;
    'PG':'(6,0)';$S;BIDI;
    'BLEED':'(7,0)';$S;BIDI;
    'VOUT_1':'(8,0)';$S;BIDI;
    'VOUT_2':'(9,0)';$S;BIDI;
    'VOUT_3':'(10,0)';$S;BIDI;
    'VOUT_4':'(11,0)';$S;BIDI;
    'VOUT_5':'(12,0)';$S;BIDI;
    'VIN_2':'(13,0)';$S;BIDI;
    'VCC':'(0,3)';$S;
    'GND':'(0,4)';$S;
end_primitive;
primitive 'NLASB3157DFT2G_SC88-G223-10187A';body 'NLASB3157DFT2G_SC88';
    'B1':'(1,0)';$S;BIDI;
    'B0':'(3,0)';$S;BIDI;
    'A':'(4,0)';$S;BIDI;
    'SELECT':'(6,0)';$S;BIDI;
    'GND':'(0,2)';$S;
    'VCC':'(0,5)';$S;
end_primitive;
primitive 'NULL-G380-10013-01';body 'NULL';
end_primitive;
primitive 'NUT-A200-00029-FB';body 'NUT';
    '1':'(1)';
end_primitive;
primitive 'NUT-G340-10437-01';body 'NUT';
    '1':'(1)';
end_primitive;
primitive 'OPTICAL-G170-10143-01';body 'OPTICAL';
    'A':'(A)';BIDI;
    'C':'(C)';BIDI;
end_primitive;
primitive 'OSC6P_V2-A130-00003-AW';body 'OSC6P_V2';
    'OE':'(1)';IN;
    'NC':'(2)';
    'GND':'(3)';
    'OUT_P':'(4)';OUT;
    'OUT_N':'(5)';OUT;
    'VDD':'(6)';
end_primitive;
primitive 'OSC6P_V2-A130-00004-AW';body 'OSC6P_V2';
    'OE':'(1)';IN;
    'NC':'(2)';
    'GND':'(3)';
    'OUT_P':'(4)';OUT;
    'OUT_N':'(5)';OUT;
    'VDD':'(6)';
end_primitive;
primitive 'PCA9508DP_TSSOP8-G223-10278-01';body 'PCA9508DP_TSSOP8';
    'SCLA':'(2,0)';$S;BIDI;
    'SDAA':'(3,0)';$S;BIDI;
    'EN':'(5,0)';$S;IN;
    'SDAB':'(6,0)';$S;BIDI;
    'SCLB':'(7,0)';$S;BIDI;
    'VCC_A':'(0,1)';$S;
    'GND':'(0,4)';$S;
    'VCC_B':'(0,8)';$S;
end_primitive;
primitive 'PCA9546APW_TSSOP16-G223-10280-A';body 'PCA9546APW_TSSOP16';
    'A0':'(1,0)';$S;IN;
    'A1':'(2,0)';$S;IN;
    'RESET*':'(3,0)';$S;IN;
    'SD0':'(4,0)';$S;BIDI;
    'SC0':'(5,0)';$S;BIDI;
    'SD1':'(6,0)';$S;BIDI;
    'SC1':'(7,0)';$S;BIDI;
    'SD2':'(9,0)';$S;BIDI;
    'SC2':'(10,0)';$S;BIDI;
    'SD3':'(11,0)';$S;BIDI;
    'SC3':'(12,0)';$S;BIDI;
    'A2':'(13,0)';$S;IN;
    'SCL':'(14,0)';$S;BIDI;
    'SDA':'(15,0)';$S;BIDI;
    'VSS':'(0,8)';$S;
    'VDD':'(0,16)';$S;
end_primitive;
primitive 'POWERMOS_3P_NCH_V1-G121-10200-A';body 'POWERMOS_3P_NCH_V1';
    'G':'(1)';BIDI;
    'S':'(2)';BIDI;
    'D':'(3)';BIDI;
end_primitive;
primitive 'POWERMOS_3P_PCH-G121-10216-01';body 'POWERMOS_3P_PCH';
    'G':'(1)';BIDI;
    'S':'(2)';BIDI;
    'D':'(3)';BIDI;
end_primitive;
primitive 'RESISTOR-A155-05101-DL,5.1KOHMA';body 'RESISTOR';
    '2':'(2)';
    '1':'(1)';
end_primitive;
primitive 'RESISTOR-G152-00055-01,1.13KOHA';body 'RESISTOR';
    '2':'(2)';
    '1':'(1)';
end_primitive;
primitive 'RESISTOR-G152-10344-01,30KOHM,A';body 'RESISTOR';
    '2':'(2)';
    '1':'(1)';
end_primitive;
primitive 'RESISTOR-G155-01202-01,12KOHM,A';body 'RESISTOR';
    '2':'(2)';
    '1':'(1)';
end_primitive;
primitive 'RESISTOR-G155-01203-01,120KOHMA';body 'RESISTOR';
    '2':'(2)';
    '1':'(1)';
end_primitive;
primitive 'RESISTOR-G155-02101-01,2.1KOHMA';body 'RESISTOR';
    '2':'(2)';
    '1':'(1)';
end_primitive;
primitive 'RESISTOR-G155-02262-01,22.6K,1%';body 'RESISTOR';
    '2':'(2)';
    '1':'(1)';
end_primitive;
primitive 'RESISTOR-G155-02402-01,24KOHM,A';body 'RESISTOR';
    '2':'(2)';
    '1':'(1)';
end_primitive;
primitive 'RESISTOR-G155-02672-01,26.7K,1%';body 'RESISTOR';
    '2':'(2)';
    '1':'(1)';
end_primitive;
primitive 'RESISTOR-G155-03001-01,3KOHM,1%';body 'RESISTOR';
    '2':'(2)';
    '1':'(1)';
end_primitive;
primitive 'RESISTOR-G155-03241-01,3.24KOHA';body 'RESISTOR';
    '2':'(2)';
    '1':'(1)';
end_primitive;
primitive 'RESISTOR-G155-03322-01,33.2KOHA';body 'RESISTOR';
    '2':'(2)';
    '1':'(1)';
end_primitive;
primitive 'RESISTOR-G155-03921-01,3.92KOHA';body 'RESISTOR';
    '2':'(2)';
    '1':'(1)';
end_primitive;
primitive 'RESISTOR-G155-04221-01,4.22KOHA';body 'RESISTOR';
    '2':'(2)';
    '1':'(1)';
end_primitive;
primitive 'RESISTOR-G155-04421-01,4.42KOHA';body 'RESISTOR';
    '2':'(2)';
    '1':'(1)';
end_primitive;
primitive 'RESISTOR-G155-05101-01,5.1KOHMA';body 'RESISTOR';
    '2':'(2)';
    '1':'(1)';
end_primitive;
primitive 'RESISTOR-G155-100R0-J0,0OHM,-';body 'RESISTOR';
    '2':'(2)';
    '1':'(1)';
end_primitive;
primitive 'RESISTOR-G155-11000-01,100OHM,A';body 'RESISTOR';
    '2':'(2)';
    '1':'(1)';
end_primitive;
primitive 'RESISTOR-G155-11001-01,1KOHM,1%';body 'RESISTOR';
    '2':'(2)';
    '1':'(1)';
end_primitive;
primitive 'RESISTOR-G155-11002-01,10KOHM,A';body 'RESISTOR';
    '2':'(2)';
    '1':'(1)';
end_primitive;
primitive 'RESISTOR-G155-11003-01,100KOHMA';body 'RESISTOR';
    '2':'(2)';
    '1':'(1)';
end_primitive;
primitive 'RESISTOR-G155-11004-01,1MOHM,1%';body 'RESISTOR';
    '2':'(2)';
    '1':'(1)';
end_primitive;
primitive 'RESISTOR-G155-11500-01,150OHM,A';body 'RESISTOR';
    '2':'(2)';
    '1':'(1)';
end_primitive;
primitive 'RESISTOR-G155-11502-01,15KOHM,A';body 'RESISTOR';
    '2':'(2)';
    '1':'(1)';
end_primitive;
primitive 'RESISTOR-G155-12002-01,20KOHM,A';body 'RESISTOR';
    '2':'(2)';
    '1':'(1)';
end_primitive;
primitive 'RESISTOR-G155-120R0-01,20OHM,1%';body 'RESISTOR';
    '2':'(2)';
    '1':'(1)';
end_primitive;
primitive 'RESISTOR-G155-12201-01,2.2KOHMA';body 'RESISTOR';
    '2':'(2)';
    '1':'(1)';
end_primitive;
primitive 'RESISTOR-G155-13300-01,330OHM,A';body 'RESISTOR';
    '2':'(2)';
    '1':'(1)';
end_primitive;
primitive 'RESISTOR-G155-133R0-01,33OHM,1%';body 'RESISTOR';
    '2':'(2)';
    '1':'(1)';
end_primitive;
primitive 'RESISTOR-G155-14701-01,4.7KOHMA';body 'RESISTOR';
    '2':'(2)';
    '1':'(1)';
end_primitive;
primitive 'RESISTOR-G155-149R9-01,49.9OHMA';body 'RESISTOR';
    '2':'(2)';
    '1':'(1)';
end_primitive;
primitive 'RESISTOR-G156-049R9-01,49.9OHMA';body 'RESISTOR';
    '2':'(2)';
    '1':'(1)';
end_primitive;
primitive 'RESISTOR-G156-100R0-J0,0OHM,-';body 'RESISTOR';
    '2':'(2)';
    '1':'(1)';
end_primitive;
primitive 'RESISTOR-G157-100R0-J0,0OHM,-';body 'RESISTOR';
    '2':'(2)';
    '1':'(1)';
end_primitive;
primitive 'RESISTOR-G157-12R20-01,2.2OHM,A';body 'RESISTOR';
    '2':'(2)';
    '1':'(1)';
end_primitive;
primitive 'SHT31A_DIS_B10KS_DFN8-A222-000A';body 'SHT31A_DIS_B10KS_DFN8';
    'SDA':'(1)';BIDI;
    'ADDR':'(2)';IN;
    'ALERT':'(3)';OUT;
    'SCL':'(4)';BIDI;
    'VDD':'(5)';
    'RESET*':'(6)';IN;
    'R':'(7)';BIDI;
    'VSS':'(8)';
    'THRM_PAD':'(9)';
end_primitive;
primitive 'SOLDER_PREFORM-G380-10015-01';body 'SOLDER_PREFORM';
    '1':'(1)';BIDI;
    '2':'(2)';BIDI;
end_primitive;
primitive 'TPS2051BDBVT_SOT23_5-G220-1033A';body 'TPS2051BDBVT_SOT23_5';
    'OUT':'(1,0)';$S;OUT;
    'OC*':'(3,0)';$S;OUT;
    'IN':'(5,0)';$S;IN;
    'EN':'(4,0)';$S;IN;
    'GND':'(0,2)';$S;
end_primitive;
primitive 'TPS3808G18DBVR_SOT23_6-G222-00A';body 'TPS3808G18DBVR_SOT23_6';
    'RESET*':'(1)';OUT;
    'GND':'(2)';
    'MR*':'(3)';BIDI;
    'CT':'(4)';BIDI;
    'SENSE':'(5)';BIDI;
    'VDD':'(6)';
end_primitive;
primitive 'TPS54824RNVR_VQFN18-G220-10657A';body 'TPS54824RNVR_VQFN18';
    'BOOT':'(1)';IN;
    'VIN_1':'(2)';IN;
    'PGND_1':'(3)';
    'PGND_2':'(4)';
    'PGND_3':'(5)';
    'SW_1':'(6)';OUT;
    'SW_2':'(7)';OUT;
    'PGND_4':'(8)';
    'PGND_5':'(9)';
    'PGND_6':'(10)';
    'VIN_2':'(11)';
    'AGND':'(12)';
    'RT/CLK':'(13)';IN;
    'FB':'(14)';IN;
    'COMP':'(15)';IN;
    'SS/TRK':'(16)';IN;
    'EN':'(17)';IN;
    'PGOOD':'(18)';OUT;
end_primitive;
primitive 'TP_PIONT-TP010CT020B030_PTH-TPA';body 'TP_PIONT';
    '1':'(1)';
end_primitive;
primitive 'TS3A5018PWR_TSSOP16-G220-10324A';body 'TS3A5018PWR_TSSOP16';
    'COM1':'(4,0)';$S;BIDI;
    'COM2':'(7,0)';$S;BIDI;
    'COM3':'(9,0)';$S;BIDI;
    'COM4':'(12,0)';$S;BIDI;
    'EN*':'(15,0)';$S;BIDI;
    'IN':'(1,0)';$S;BIDI;
    'NC1':'(2,0)';$S;BIDI;
    'NC2':'(5,0)';$S;BIDI;
    'NC3':'(11,0)';$S;BIDI;
    'NC4':'(14,0)';$S;BIDI;
    'NO1':'(3,0)';$S;BIDI;
    'NO2':'(6,0)';$S;BIDI;
    'NO3':'(10,0)';$S;BIDI;
    'NO4':'(13,0)';$S;BIDI;
    'GND':'(0,8)';$S;
    'V_P':'(0,16)';$S;
end_primitive;
primitive 'TS3USB3031RMGR_WQFN12-G220-103A';body 'TS3USB3031RMGR_WQFN12';
    'VCC':'(12)';
    'D_P':'(11)';BIDI;
    'D_N':'(10)';BIDI;
    'SEL0':'(1)';IN;
    'SEL1':'(2)';IN;
    'USB1_P':'(3)';BIDI;
    'USB1_N':'(4)';BIDI;
    'USB2_P':'(5)';BIDI;
    'USB2_N':'(6)';BIDI;
    'MHL_P':'(7)';BIDI;
    'MHL_N':'(8)';BIDI;
    'GND':'(9)';
end_primitive;
primitive 'XC7A200T_2FBG484C_FBG484-G240-A';body 'XC7A200T_2FBG484C_FBG484';
    'CCLK_0':'(L12,0,0,0,0)';$S;BIDI;
    'CFGBVS_0':'(U8,0,0,0,0)';$S;IN;
    'DONE_0':'(G11,0,0,0,0)';$S;BIDI;
    'DXN_0':'(N9,0,0,0,0)';$S;IN;
    'DXP_0':'(N10,0,0,0,0)';$S;IN;
    'INIT_0*':'(U12,0,0,0,0)';$S;BIDI;
    'M0_0':'(U11,0,0,0,0)';$S;IN;
    'M1_0':'(U10,0,0,0,0)';$S;IN;
    'M2_0':'(U9,0,0,0,0)';$S;IN;
    'MGTPRXN0_216':'(A8,0,0,0,0)';$S;IN;
    'MGTPRXN1_216':'(C11,0,0,0,0)';$S;IN;
    'MGTPRXN2_216':'(A10,0,0,0,0)';$S;IN;
    'MGTPRXN3_216':'(C9,0,0,0,0)';$S;IN;
    'MGTPRXP0_216':'(B8,0,0,0,0)';$S;IN;
    'MGTPRXP1_216':'(D11,0,0,0,0)';$S;IN;
    'MGTPRXP2_216':'(B10,0,0,0,0)';$S;IN;
    'MGTPRXP3_216':'(D9,0,0,0,0)';$S;IN;
    'MGTPTXN0_216':'(A4,0,0,0,0)';$S;OUT;
    'MGTPTXN1_216':'(C5,0,0,0,0)';$S;OUT;
    'MGTPTXN2_216':'(A6,0,0,0,0)';$S;OUT;
    'MGTPTXN3_216':'(C7,0,0,0,0)';$S;OUT;
    'MGTPTXP0_216':'(B4,0,0,0,0)';$S;OUT;
    'MGTPTXP1_216':'(D5,0,0,0,0)';$S;OUT;
    'MGTPTXP2_216':'(B6,0,0,0,0)';$S;OUT;
    'MGTPTXP3_216':'(D7,0,0,0,0)';$S;OUT;
    'MGTREFCLK0N_216':'(E6,0,0,0,0)';$S;IN;
    'MGTREFCLK0P_216':'(F6,0,0,0,0)';$S;IN;
    'MGTREFCLK1N_216':'(E10,0,0,0,0)';$S;IN;
    'MGTREFCLK1P_216':'(F10,0,0,0,0)';$S;IN;
    'MGTRREF_216':'(F8,0,0,0,0)';$S;IN;
    'PROGRAM_0*':'(N12,0,0,0,0)';$S;BIDI;
    'TCK_0':'(V12,0,0,0,0)';$S;IN;
    'TDI_0':'(R13,0,0,0,0)';$S;IN;
    'TDO_0':'(U13,0,0,0,0)';$S;OUT;
    'TMS_0':'(T13,0,0,0,0)';$S;IN;
    'VN_0':'(M9,0,0,0,0)';$S;IN;
    'VP_0':'(L10,0,0,0,0)';$S;IN;
    'VREFN_0':'(L9,0,0,0,0)';$S;BIDI;
    'VREFP_0':'(M10,0,0,0,0)';$S;BIDI;
    'IO_0_13':'(0,Y17,0,0,0)';$S;BIDI;
    'IO_0_14':'(0,P20,0,0,0)';$S;BIDI;
    'IO_25_14':'(0,N15,0,0,0)';$S;BIDI;
    'IO_L1N_T0_13':'(0,AA16,0,0,0)';$S;BIDI;
    'IO_L1N_T0_D01_DIN_14':'(0,R22,0,0,0)';$S;BIDI;
    'IO_L1P_T0_13':'(0,Y16,0,0,0)';$S;BIDI;
    'IO_L1P_T0_D00_MOSI_14':'(0,P22,0,0,0)';$S;BIDI;
    'IO_L2N_T0_13':'(0,AB17,0,0,0)';$S;BIDI;
    'IO_L2N_T0_D03_14':'(0,R21,0,0,0)';$S;BIDI;
    'IO_L2P_T0_13':'(0,AB16,0,0,0)';$S;BIDI;
    'IO_L2P_T0_D02_14':'(0,P21,0,0,0)';$S;BIDI;
    'IO_L3N_T0_DQS_13':'(0,AB13,0,0,0)';$S;BIDI;
    'IO_L3N_T0_DQS_EMCCLK_14':'(0,V22,0,0,0)';$S;BIDI;
    'IO_L3P_T0_DQS_13':'(0,AA13,0,0,0)';$S;BIDI;
    'IO_L3P_T0_DQS_PUDC_14*':'(0,U22,0,0,0)';$S;BIDI;
    'IO_L4N_T0_13':'(0,AB15,0,0,0)';$S;BIDI;
    'IO_L4N_T0_D05_14':'(0,U21,0,0,0)';$S;BIDI;
    'IO_L4P_T0_13':'(0,AA15,0,0,0)';$S;BIDI;
    'IO_L4P_T0_D04_14':'(0,T21,0,0,0)';$S;BIDI;
    'IO_L5N_T0_13':'(0,AA14,0,0,0)';$S;BIDI;
    'IO_L5N_T0_D07_14':'(0,R19,0,0,0)';$S;BIDI;
    'IO_L5P_T0_13':'(0,Y13,0,0,0)';$S;BIDI;
    'IO_L5P_T0_D06_14':'(0,P19,0,0,0)';$S;BIDI;
    'IO_L6N_T0_D08_VREF_14':'(0,T20,0,0,0)';$S;BIDI;
    'IO_L6N_T0_VREF_13':'(0,Y14,0,0,0)';$S;BIDI;
    'IO_L6P_T0_13':'(0,W14,0,0,0)';$S;BIDI;
    'IO_L6P_T0_FCS_B_14':'(0,T19,0,0,0)';$S;BIDI;
    'IO_L7N_T1_13':'(0,AB12,0,0,0)';$S;BIDI;
    'IO_L7N_T1_D10_14':'(0,W22,0,0,0)';$S;BIDI;
    'IO_L7P_T1_13':'(0,AB11,0,0,0)';$S;BIDI;
    'IO_L7P_T1_D09_14':'(0,W21,0,0,0)';$S;BIDI;
    'IO_L8N_T1_13':'(0,AB10,0,0,0)';$S;BIDI;
    'IO_L8N_T1_D12_14':'(0,AA21,0,0,0)';$S;BIDI;
    'IO_L8P_T1_13':'(0,AA9,0,0,0)';$S;BIDI;
    'IO_L8P_T1_D11_14':'(0,AA20,0,0,0)';$S;BIDI;
    'IO_L9N_T1_DQS_13':'(0,AA11,0,0,0)';$S;BIDI;
    'IO_L9N_T1_DQS_D13_14':'(0,Y22,0,0,0)';$S;BIDI;
    'IO_L9P_T1_DQS_13':'(0,AA10,0,0,0)';$S;BIDI;
    'IO_L9P_T1_DQS_14':'(0,Y21,0,0,0)';$S;BIDI;
    'IO_L10N_T1_13':'(0,W10,0,0,0)';$S;BIDI;
    'IO_L10N_T1_D15_14':'(0,AB22,0,0,0)';$S;BIDI;
    'IO_L10P_T1_13':'(0,V10,0,0,0)';$S;BIDI;
    'IO_L10P_T1_D14_14':'(0,AB21,0,0,0)';$S;BIDI;
    'IO_L11N_T1_SRCC_13':'(0,Y12,0,0,0)';$S;BIDI;
    'IO_L11N_T1_SRCC_14':'(0,V20,0,0,0)';$S;BIDI;
    'IO_L11P_T1_SRCC_13':'(0,Y11,0,0,0)';$S;BIDI;
    'IO_L11P_T1_SRCC_14':'(0,U20,0,0,0)';$S;BIDI;
    'IO_L12N_T1_MRCC_13':'(0,W12,0,0,0)';$S;BIDI;
    'IO_L12N_T1_MRCC_14':'(0,W20,0,0,0)';$S;BIDI;
    'IO_L12P_T1_MRCC_13':'(0,W11,0,0,0)';$S;BIDI;
    'IO_L12P_T1_MRCC_14':'(0,W19,0,0,0)';$S;BIDI;
    'IO_L13N_T2_MRCC_13':'(0,V14,0,0,0)';$S;BIDI;
    'IO_L13N_T2_MRCC_14':'(0,Y19,0,0,0)';$S;BIDI;
    'IO_L13P_T2_MRCC_13':'(0,V13,0,0,0)';$S;BIDI;
    'IO_L13P_T2_MRCC_14':'(0,Y18,0,0,0)';$S;BIDI;
    'IO_L14N_T2_SRCC_13':'(0,V15,0,0,0)';$S;BIDI;
    'IO_L14N_T2_SRCC_14':'(0,V19,0,0,0)';$S;BIDI;
    'IO_L14P_T2_SRCC_13':'(0,U15,0,0,0)';$S;BIDI;
    'IO_L14P_T2_SRCC_14':'(0,V18,0,0,0)';$S;BIDI;
    'IO_L15N_T2_DQS_13':'(0,T15,0,0,0)';$S;BIDI;
    'IO_L15N_T2_DQS_DOUT_CSO_14*':'(0,AB20,0,0,0)';$S;BIDI;
    'IO_L15P_T2_DQS_13':'(0,T14,0,0,0)';$S;BIDI;
    'IO_L15P_T2_DQS_RDWR_14*':'(0,AA19,0,0,0)';$S;BIDI;
    'IO_L16N_T2_13':'(0,W16,0,0,0)';$S;BIDI;
    'IO_L16N_T2_A15_D31_14':'(0,W17,0,0,0)';$S;BIDI;
    'IO_L16P_T2_13':'(0,W15,0,0,0)';$S;BIDI;
    'IO_L16P_T2_CSI_14*':'(0,V17,0,0,0)';$S;BIDI;
    'IO_L17N_T2_13':'(0,U16,0,0,0)';$S;BIDI;
    'IO_L17N_T2_A13_D29_14':'(0,AB18,0,0,0)';$S;BIDI;
    'IO_L17P_T2_13':'(0,T16,0,0,0)';$S;BIDI;
    'IO_L17P_T2_A14_D30_14':'(0,AA18,0,0,0)';$S;BIDI;
    'IO_L18N_T2_A11_D27_14':'(0,U18,0,0,0)';$S;BIDI;
    'IO_L18P_T2_A12_D28_14':'(0,U17,0,0,0)';$S;BIDI;
    'IO_L19N_T3_A09_D25_VREF_14':'(0,R14,0,0,0)';$S;BIDI;
    'IO_L19P_T3_A10_D26_14':'(0,P14,0,0,0)';$S;BIDI;
    'IO_L20N_T3_A07_D23_14':'(0,T18,0,0,0)';$S;BIDI;
    'IO_L20P_T3_A08_D24_14':'(0,R18,0,0,0)';$S;BIDI;
    'IO_L21N_T3_DQS_A06_D22_14':'(0,P17,0,0,0)';$S;BIDI;
    'IO_L21P_T3_DQS_14':'(0,N17,0,0,0)';$S;BIDI;
    'IO_L22N_T3_A04_D20_14':'(0,R16,0,0,0)';$S;BIDI;
    'IO_L22P_T3_A05_D21_14':'(0,P15,0,0,0)';$S;BIDI;
    'IO_L23N_T3_A02_D18_14':'(0,N14,0,0,0)';$S;BIDI;
    'IO_L23P_T3_A03_D19_14':'(0,N13,0,0,0)';$S;BIDI;
    'IO_L24N_T3_A00_D16_14':'(0,R17,0,0,0)';$S;BIDI;
    'IO_L24P_T3_A01_D17_14':'(0,P16,0,0,0)';$S;BIDI;
    'IO_0_15':'(0,0,J16,0,0)';$S;BIDI;
    'IO_0_16':'(0,0,F15,0,0)';$S;BIDI;
    'IO_25_15':'(0,0,M17,0,0)';$S;BIDI;
    'IO_25_16':'(0,0,F21,0,0)';$S;BIDI;
    'IO_L1N_T0_16':'(0,0,F14,0,0)';$S;BIDI;
    'IO_L1N_T0_AD0N_15':'(0,0,G13,0,0)';$S;BIDI;
    'IO_L1P_T0_16':'(0,0,F13,0,0)';$S;BIDI;
    'IO_L1P_T0_AD0P_15':'(0,0,H13,0,0)';$S;BIDI;
    'IO_L2N_T0_16':'(0,0,E17,0,0)';$S;BIDI;
    'IO_L2N_T0_AD8N_15':'(0,0,G16,0,0)';$S;BIDI;
    'IO_L2P_T0_16':'(0,0,F16,0,0)';$S;BIDI;
    'IO_L2P_T0_AD8P_15':'(0,0,G15,0,0)';$S;BIDI;
    'IO_L3N_T0_DQS_16':'(0,0,C15,0,0)';$S;BIDI;
    'IO_L3N_T0_DQS_AD1N_15':'(0,0,H14,0,0)';$S;BIDI;
    'IO_L3P_T0_DQS_16':'(0,0,C14,0,0)';$S;BIDI;
    'IO_L3P_T0_DQS_AD1P_15':'(0,0,J14,0,0)';$S;BIDI;
    'IO_L4N_T0_15':'(0,0,G18,0,0)';$S;BIDI;
    'IO_L4N_T0_16':'(0,0,E14,0,0)';$S;BIDI;
    'IO_L4P_T0_15':'(0,0,G17,0,0)';$S;BIDI;
    'IO_L4P_T0_16':'(0,0,E13,0,0)';$S;BIDI;
    'IO_L5N_T0_16':'(0,0,D16,0,0)';$S;BIDI;
    'IO_L5N_T0_AD9N_15':'(0,0,H15,0,0)';$S;BIDI;
    'IO_L5P_T0_16':'(0,0,E16,0,0)';$S;BIDI;
    'IO_L5P_T0_AD9P_15':'(0,0,J15,0,0)';$S;BIDI;
    'IO_L6N_T0_VREF_15':'(0,0,H18,0,0)';$S;BIDI;
    'IO_L6N_T0_VREF_16':'(0,0,D15,0,0)';$S;BIDI;
    'IO_L6P_T0_15':'(0,0,H17,0,0)';$S;BIDI;
    'IO_L6P_T0_16':'(0,0,D14,0,0)';$S;BIDI;
    'IO_L7N_T1_16':'(0,0,B16,0,0)';$S;BIDI;
    'IO_L7N_T1_AD2N_15':'(0,0,H22,0,0)';$S;BIDI;
    'IO_L7P_T1_16':'(0,0,B15,0,0)';$S;BIDI;
    'IO_L7P_T1_AD2P_15':'(0,0,J22,0,0)';$S;BIDI;
    'IO_L8N_T1_16':'(0,0,B13,0,0)';$S;BIDI;
    'IO_L8N_T1_AD10N_15':'(0,0,G20,0,0)';$S;BIDI;
    'IO_L8P_T1_16':'(0,0,C13,0,0)';$S;BIDI;
    'IO_L8P_T1_AD10P_15':'(0,0,H20,0,0)';$S;BIDI;
    'IO_L9N_T1_DQS_16':'(0,0,A16,0,0)';$S;BIDI;
    'IO_L9N_T1_DQS_AD3N_15':'(0,0,K22,0,0)';$S;BIDI;
    'IO_L9P_T1_DQS_16':'(0,0,A15,0,0)';$S;BIDI;
    'IO_L9P_T1_DQS_AD3P_15':'(0,0,K21,0,0)';$S;BIDI;
    'IO_L10N_T1_16':'(0,0,A14,0,0)';$S;BIDI;
    'IO_L10N_T1_AD11N_15':'(0,0,L21,0,0)';$S;BIDI;
    'IO_L10P_T1_16':'(0,0,A13,0,0)';$S;BIDI;
    'IO_L10P_T1_AD11P_15':'(0,0,M21,0,0)';$S;BIDI;
    'IO_L11N_T1_SRCC_15':'(0,0,J21,0,0)';$S;BIDI;
    'IO_L11N_T1_SRCC_16':'(0,0,B18,0,0)';$S;BIDI;
    'IO_L11P_T1_SRCC_15':'(0,0,J20,0,0)';$S;BIDI;
    'IO_L11P_T1_SRCC_16':'(0,0,B17,0,0)';$S;BIDI;
    'IO_L12N_T1_MRCC_15':'(0,0,H19,0,0)';$S;BIDI;
    'IO_L12N_T1_MRCC_16':'(0,0,C17,0,0)';$S;BIDI;
    'IO_L12P_T1_MRCC_15':'(0,0,J19,0,0)';$S;BIDI;
    'IO_L12P_T1_MRCC_16':'(0,0,D17,0,0)';$S;BIDI;
    'IO_L13N_T2_MRCC_15':'(0,0,K19,0,0)';$S;BIDI;
    'IO_L13N_T2_MRCC_16':'(0,0,C19,0,0)';$S;BIDI;
    'IO_L13P_T2_MRCC_15':'(0,0,K18,0,0)';$S;BIDI;
    'IO_L13P_T2_MRCC_16':'(0,0,C18,0,0)';$S;BIDI;
    'IO_L14N_T2_SRCC_15':'(0,0,L20,0,0)';$S;BIDI;
    'IO_L14N_T2_SRCC_16':'(0,0,D19,0,0)';$S;BIDI;
    'IO_L14P_T2_SRCC_15':'(0,0,L19,0,0)';$S;BIDI;
    'IO_L14P_T2_SRCC_16':'(0,0,E19,0,0)';$S;BIDI;
    'IO_L15N_T2_DQS_16':'(0,0,E18,0,0)';$S;BIDI;
    'IO_L15N_T2_DQS_ADV_B_15':'(0,0,M22,0,0)';$S;BIDI;
    'IO_L15P_T2_DQS_15':'(0,0,N22,0,0)';$S;BIDI;
    'IO_L15P_T2_DQS_16':'(0,0,F18,0,0)';$S;BIDI;
    'IO_L16N_T2_16':'(0,0,A20,0,0)';$S;BIDI;
    'IO_L16N_T2_A27_15':'(0,0,L18,0,0)';$S;BIDI;
    'IO_L16P_T2_16':'(0,0,B20,0,0)';$S;BIDI;
    'IO_L16P_T2_A28_15':'(0,0,M18,0,0)';$S;BIDI;
    'IO_L17N_T2_16':'(0,0,A19,0,0)';$S;BIDI;
    'IO_L17N_T2_A25_15':'(0,0,N19,0,0)';$S;BIDI;
    'IO_L17P_T2_16':'(0,0,A18,0,0)';$S;BIDI;
    'IO_L17P_T2_A26_15':'(0,0,N18,0,0)';$S;BIDI;
    'IO_L18N_T2_16':'(0,0,F20,0,0)';$S;BIDI;
    'IO_L18N_T2_A23_15':'(0,0,M20,0,0)';$S;BIDI;
    'IO_L18P_T2_16':'(0,0,F19,0,0)';$S;BIDI;
    'IO_L18P_T2_A24_15':'(0,0,N20,0,0)';$S;BIDI;
    'IO_L19N_T3_A21_VREF_15':'(0,0,K14,0,0)';$S;BIDI;
    'IO_L19N_T3_VREF_16':'(0,0,C20,0,0)';$S;BIDI;
    'IO_L19P_T3_16':'(0,0,D20,0,0)';$S;BIDI;
    'IO_L19P_T3_A22_15':'(0,0,K13,0,0)';$S;BIDI;
    'IO_L20N_T3_16':'(0,0,B22,0,0)';$S;BIDI;
    'IO_L20N_T3_A19_15':'(0,0,L13,0,0)';$S;BIDI;
    'IO_L20P_T3_16':'(0,0,C22,0,0)';$S;BIDI;
    'IO_L20P_T3_A20_15':'(0,0,M13,0,0)';$S;BIDI;
    'IO_L21N_T3_DQS_16':'(0,0,A21,0,0)';$S;BIDI;
    'IO_L21N_T3_DQS_A18_15':'(0,0,J17,0,0)';$S;BIDI;
    'IO_L21P_T3_DQS_15':'(0,0,K17,0,0)';$S;BIDI;
    'IO_L21P_T3_DQS_16':'(0,0,B21,0,0)';$S;BIDI;
    'IO_L22N_T3_16':'(0,0,D22,0,0)';$S;BIDI;
    'IO_L22N_T3_A16_15':'(0,0,L15,0,0)';$S;BIDI;
    'IO_L22P_T3_16':'(0,0,E22,0,0)';$S;BIDI;
    'IO_L22P_T3_A17_15':'(0,0,L14,0,0)';$S;BIDI;
    'IO_L23N_T3_16':'(0,0,D21,0,0)';$S;BIDI;
    'IO_L23N_T3_FWE_B_15':'(0,0,K16,0,0)';$S;BIDI;
    'IO_L23P_T3_16':'(0,0,E21,0,0)';$S;BIDI;
    'IO_L23P_T3_FOE_B_15':'(0,0,L16,0,0)';$S;BIDI;
    'IO_L24N_T3_16':'(0,0,G22,0,0)';$S;BIDI;
    'IO_L24N_T3_RS0_15':'(0,0,M16,0,0)';$S;BIDI;
    'IO_L24P_T3_16':'(0,0,G21,0,0)';$S;BIDI;
    'IO_L24P_T3_RS1_15':'(0,0,M15,0,0)';$S;BIDI;
    'IO_0_34':'(0,0,0,T3,0)';$S;BIDI;
    'IO_0_35':'(0,0,0,F4,0)';$S;BIDI;
    'IO_25_34':'(0,0,0,U7,0)';$S;BIDI;
    'IO_25_35':'(0,0,0,L6,0)';$S;BIDI;
    'IO_L1N_T0_34':'(0,0,0,U1,0)';$S;BIDI;
    'IO_L1N_T0_AD4N_35':'(0,0,0,A1,0)';$S;BIDI;
    'IO_L1P_T0_34':'(0,0,0,T1,0)';$S;BIDI;
    'IO_L1P_T0_AD4P_35':'(0,0,0,B1,0)';$S;BIDI;
    'IO_L2N_T0_34':'(0,0,0,V2,0)';$S;BIDI;
    'IO_L2N_T0_AD12N_35':'(0,0,0,B2,0)';$S;BIDI;
    'IO_L2P_T0_34':'(0,0,0,U2,0)';$S;BIDI;
    'IO_L2P_T0_AD12P_35':'(0,0,0,C2,0)';$S;BIDI;
    'IO_L3N_T0_DQS_34':'(0,0,0,R2,0)';$S;BIDI;
    'IO_L3N_T0_DQS_AD5N_35':'(0,0,0,D1,0)';$S;BIDI;
    'IO_L3P_T0_DQS_34':'(0,0,0,R3,0)';$S;BIDI;
    'IO_L3P_T0_DQS_AD5P_35':'(0,0,0,E1,0)';$S;BIDI;
    'IO_L4N_T0_34':'(0,0,0,Y2,0)';$S;BIDI;
    'IO_L4N_T0_35':'(0,0,0,D2,0)';$S;BIDI;
    'IO_L4P_T0_34':'(0,0,0,W2,0)';$S;BIDI;
    'IO_L4P_T0_35':'(0,0,0,E2,0)';$S;BIDI;
    'IO_L5N_T0_34':'(0,0,0,Y1,0)';$S;BIDI;
    'IO_L5N_T0_AD13N_35':'(0,0,0,F1,0)';$S;BIDI;
    'IO_L5P_T0_34':'(0,0,0,W1,0)';$S;BIDI;
    'IO_L5P_T0_AD13P_35':'(0,0,0,G1,0)';$S;BIDI;
    'IO_L6N_T0_VREF_34':'(0,0,0,V3,0)';$S;BIDI;
    'IO_L6N_T0_VREF_35':'(0,0,0,E3,0)';$S;BIDI;
    'IO_L6P_T0_34':'(0,0,0,U3,0)';$S;BIDI;
    'IO_L6P_T0_35':'(0,0,0,F3,0)';$S;BIDI;
    'IO_L7N_T1_34':'(0,0,0,AB1,0)';$S;BIDI;
    'IO_L7N_T1_AD6N_35':'(0,0,0,J1,0)';$S;BIDI;
    'IO_L7P_T1_34':'(0,0,0,AA1,0)';$S;BIDI;
    'IO_L7P_T1_AD6P_35':'(0,0,0,K1,0)';$S;BIDI;
    'IO_L8N_T1_34':'(0,0,0,AB2,0)';$S;BIDI;
    'IO_L8N_T1_AD14N_35':'(0,0,0,G2,0)';$S;BIDI;
    'IO_L8P_T1_34':'(0,0,0,AB3,0)';$S;BIDI;
    'IO_L8P_T1_AD14P_35':'(0,0,0,H2,0)';$S;BIDI;
    'IO_L9N_T1_DQS_34':'(0,0,0,AA3,0)';$S;BIDI;
    'IO_L9N_T1_DQS_AD7N_35':'(0,0,0,J2,0)';$S;BIDI;
    'IO_L9P_T1_DQS_34':'(0,0,0,Y3,0)';$S;BIDI;
    'IO_L9P_T1_DQS_AD7P_35':'(0,0,0,K2,0)';$S;BIDI;
    'IO_L10N_T1_34':'(0,0,0,AB5,0)';$S;BIDI;
    'IO_L10N_T1_AD15N_35':'(0,0,0,H5,0)';$S;BIDI;
    'IO_L10P_T1_34':'(0,0,0,AA5,0)';$S;BIDI;
    'IO_L10P_T1_AD15P_35':'(0,0,0,J5,0)';$S;BIDI;
    'IO_L11N_T1_SRCC_34':'(0,0,0,AA4,0)';$S;BIDI;
    'IO_L11N_T1_SRCC_35':'(0,0,0,G3,0)';$S;BIDI;
    'IO_L11P_T1_SRCC_34':'(0,0,0,Y4,0)';$S;BIDI;
    'IO_L11P_T1_SRCC_35':'(0,0,0,H3,0)';$S;BIDI;
    'IO_L12N_T1_MRCC_34':'(0,0,0,W4,0)';$S;BIDI;
    'IO_L12N_T1_MRCC_35':'(0,0,0,G4,0)';$S;BIDI;
    'IO_L12P_T1_MRCC_34':'(0,0,0,V4,0)';$S;BIDI;
    'IO_L12P_T1_MRCC_35':'(0,0,0,H4,0)';$S;BIDI;
    'IO_L13N_T2_MRCC_34':'(0,0,0,T4,0)';$S;BIDI;
    'IO_L13N_T2_MRCC_35':'(0,0,0,J4,0)';$S;BIDI;
    'IO_L13P_T2_MRCC_34':'(0,0,0,R4,0)';$S;BIDI;
    'IO_L13P_T2_MRCC_35':'(0,0,0,K4,0)';$S;BIDI;
    'IO_L14N_T2_SRCC_34':'(0,0,0,U5,0)';$S;BIDI;
    'IO_L14N_T2_SRCC_35':'(0,0,0,K3,0)';$S;BIDI;
    'IO_L14P_T2_SRCC_34':'(0,0,0,T5,0)';$S;BIDI;
    'IO_L14P_T2_SRCC_35':'(0,0,0,L3,0)';$S;BIDI;
    'IO_L15N_T2_DQS_34':'(0,0,0,W5,0)';$S;BIDI;
    'IO_L15N_T2_DQS_35':'(0,0,0,L1,0)';$S;BIDI;
    'IO_L15P_T2_DQS_34':'(0,0,0,W6,0)';$S;BIDI;
    'IO_L15P_T2_DQS_35':'(0,0,0,M1,0)';$S;BIDI;
    'IO_L16N_T2_34':'(0,0,0,V5,0)';$S;BIDI;
    'IO_L16N_T2_35':'(0,0,0,M2,0)';$S;BIDI;
    'IO_L16P_T2_34':'(0,0,0,U6,0)';$S;BIDI;
    'IO_L16P_T2_35':'(0,0,0,M3,0)';$S;BIDI;
    'IO_L17N_T2_34':'(0,0,0,T6,0)';$S;BIDI;
    'IO_L17N_T2_35':'(0,0,0,J6,0)';$S;BIDI;
    'IO_L17P_T2_34':'(0,0,0,R6,0)';$S;BIDI;
    'IO_L17P_T2_35':'(0,0,0,K6,0)';$S;BIDI;
    'IO_L18N_T2_34':'(0,0,0,AA6,0)';$S;BIDI;
    'IO_L18N_T2_35':'(0,0,0,L4,0)';$S;BIDI;
    'IO_L18P_T2_34':'(0,0,0,Y6,0)';$S;BIDI;
    'IO_L18P_T2_35':'(0,0,0,L5,0)';$S;BIDI;
    'IO_L19N_T3_VREF_34':'(0,0,0,W7,0)';$S;BIDI;
    'IO_L19N_T3_VREF_35':'(0,0,0,N3,0)';$S;BIDI;
    'IO_L19P_T3_34':'(0,0,0,V7,0)';$S;BIDI;
    'IO_L19P_T3_35':'(0,0,0,N4,0)';$S;BIDI;
    'IO_L20N_T3_34':'(0,0,0,AB6,0)';$S;BIDI;
    'IO_L20N_T3_35':'(0,0,0,P1,0)';$S;BIDI;
    'IO_L20P_T3_34':'(0,0,0,AB7,0)';$S;BIDI;
    'IO_L20P_T3_35':'(0,0,0,R1,0)';$S;BIDI;
    'IO_L21N_T3_DQS_34':'(0,0,0,V8,0)';$S;BIDI;
    'IO_L21N_T3_DQS_35':'(0,0,0,P4,0)';$S;BIDI;
    'IO_L21P_T3_DQS_34':'(0,0,0,V9,0)';$S;BIDI;
    'IO_L21P_T3_DQS_35':'(0,0,0,P5,0)';$S;BIDI;
    'IO_L22N_T3_34':'(0,0,0,AB8,0)';$S;BIDI;
    'IO_L22N_T3_35':'(0,0,0,N2,0)';$S;BIDI;
    'IO_L22P_T3_34':'(0,0,0,AA8,0)';$S;BIDI;
    'IO_L22P_T3_35':'(0,0,0,P2,0)';$S;BIDI;
    'IO_L23N_T3_34':'(0,0,0,Y7,0)';$S;BIDI;
    'IO_L23N_T3_35':'(0,0,0,M5,0)';$S;BIDI;
    'IO_L23P_T3_34':'(0,0,0,Y8,0)';$S;BIDI;
    'IO_L23P_T3_35':'(0,0,0,M6,0)';$S;BIDI;
    'IO_L24N_T3_34':'(0,0,0,Y9,0)';$S;BIDI;
    'IO_L24N_T3_35':'(0,0,0,N5,0)';$S;BIDI;
    'IO_L24P_T3_34':'(0,0,0,W9,0)';$S;BIDI;
    'IO_L24P_T3_35':'(0,0,0,P6,0)';$S;BIDI;
    'GNDADC_0':'(0,0,0,0,K9)';$S;
    'GND_1':'(0,0,0,0,A11)';$S;
    'GND_2':'(0,0,0,0,A12)';$S;
    'GND_3':'(0,0,0,0,A2)';$S;
    'GND_4':'(0,0,0,0,A22)';$S;
    'GND_5':'(0,0,0,0,A3)';$S;
    'GND_6':'(0,0,0,0,A5)';$S;
    'GND_7':'(0,0,0,0,A7)';$S;
    'GND_8':'(0,0,0,0,A9)';$S;
    'GND_9':'(0,0,0,0,AA12)';$S;
    'GND_10':'(0,0,0,0,AA2)';$S;
    'GND_11':'(0,0,0,0,AA22)';$S;
    'GND_12':'(0,0,0,0,AB19)';$S;
    'GND_13':'(0,0,0,0,AB9)';$S;
    'GND_14':'(0,0,0,0,B12)';$S;
    'GND_15':'(0,0,0,0,B19)';$S;
    'GND_16':'(0,0,0,0,B3)';$S;
    'GND_17':'(0,0,0,0,C10)';$S;
    'GND_18':'(0,0,0,0,C12)';$S;
    'GND_19':'(0,0,0,0,C16)';$S;
    'GND_20':'(0,0,0,0,C3)';$S;
    'GND_21':'(0,0,0,0,C6)';$S;
    'GND_22':'(0,0,0,0,D12)';$S;
    'GND_23':'(0,0,0,0,D13)';$S;
    'GND_24':'(0,0,0,0,D3)';$S;
    'GND_25':'(0,0,0,0,D4)';$S;
    'GND_26':'(0,0,0,0,D8)';$S;
    'GND_27':'(0,0,0,0,E11)';$S;
    'GND_28':'(0,0,0,0,E20)';$S;
    'GND_29':'(0,0,0,0,E4)';$S;
    'GND_30':'(0,0,0,0,E5)';$S;
    'GND_31':'(0,0,0,0,E7)';$S;
    'GND_32':'(0,0,0,0,E9)';$S;
    'GND_33':'(0,0,0,0,F11)';$S;
    'GND_34':'(0,0,0,0,F17)';$S;
    'GND_35':'(0,0,0,0,F5)';$S;
    'GND_36':'(0,0,0,0,G10)';$S;
    'GND_37':'(0,0,0,0,G12)';$S;
    'GND_38':'(0,0,0,0,G14)';$S;
    'GND_39':'(0,0,0,0,G5)';$S;
    'GND_40':'(0,0,0,0,G6)';$S;
    'GND_41':'(0,0,0,0,G7)';$S;
    'GND_42':'(0,0,0,0,G8)';$S;
    'GND_43':'(0,0,0,0,G9)';$S;
    'GND_44':'(0,0,0,0,H1)';$S;
    'GND_45':'(0,0,0,0,H11)';$S;
    'GND_46':'(0,0,0,0,H21)';$S;
    'GND_47':'(0,0,0,0,H7)';$S;
    'GND_48':'(0,0,0,0,H9)';$S;
    'GND_49':'(0,0,0,0,J10)';$S;
    'GND_50':'(0,0,0,0,J12)';$S;
    'GND_51':'(0,0,0,0,J18)';$S;
    'GND_52':'(0,0,0,0,J8)';$S;
    'GND_53':'(0,0,0,0,K11)';$S;
    'GND_54':'(0,0,0,0,K15)';$S;
    'GND_55':'(0,0,0,0,K5)';$S;
    'GND_56':'(0,0,0,0,K7)';$S;
    'GND_57':'(0,0,0,0,L2)';$S;
    'GND_58':'(0,0,0,0,L22)';$S;
    'GND_59':'(0,0,0,0,L8)';$S;
    'GND_60':'(0,0,0,0,M11)';$S;
    'GND_61':'(0,0,0,0,M19)';$S;
    'GND_62':'(0,0,0,0,M7)';$S;
    'GND_63':'(0,0,0,0,N16)';$S;
    'GND_64':'(0,0,0,0,N6)';$S;
    'GND_65':'(0,0,0,0,N8)';$S;
    'GND_66':'(0,0,0,0,P11)';$S;
    'GND_67':'(0,0,0,0,P13)';$S;
    'GND_68':'(0,0,0,0,P3)';$S;
    'GND_69':'(0,0,0,0,P7)';$S;
    'GND_70':'(0,0,0,0,P9)';$S;
    'GND_71':'(0,0,0,0,R10)';$S;
    'GND_72':'(0,0,0,0,R12)';$S;
    'GND_73':'(0,0,0,0,R20)';$S;
    'GND_74':'(0,0,0,0,R8)';$S;
    'GND_75':'(0,0,0,0,T11)';$S;
    'GND_76':'(0,0,0,0,T17)';$S;
    'GND_77':'(0,0,0,0,T7)';$S;
    'GND_78':'(0,0,0,0,T9)';$S;
    'GND_79':'(0,0,0,0,U14)';$S;
    'GND_80':'(0,0,0,0,U4)';$S;
    'GND_81':'(0,0,0,0,V1)';$S;
    'GND_82':'(0,0,0,0,V11)';$S;
    'GND_83':'(0,0,0,0,V21)';$S;
    'GND_84':'(0,0,0,0,W18)';$S;
    'GND_85':'(0,0,0,0,W8)';$S;
    'GND_86':'(0,0,0,0,Y15)';$S;
    'GND_87':'(0,0,0,0,Y5)';$S;
    'MGTAVCC_1':'(0,0,0,0,D10)';$S;
    'MGTAVCC_2':'(0,0,0,0,D6)';$S;
    'MGTAVCC_3':'(0,0,0,0,E8)';$S;
    'MGTAVCC_4':'(0,0,0,0,F7)';$S;
    'MGTAVCC_5':'(0,0,0,0,F9)';$S;
    'MGTAVTT_1':'(0,0,0,0,B11)';$S;
    'MGTAVTT_2':'(0,0,0,0,B5)';$S;
    'MGTAVTT_3':'(0,0,0,0,B7)';$S;
    'MGTAVTT_4':'(0,0,0,0,B9)';$S;
    'MGTAVTT_5':'(0,0,0,0,C4)';$S;
    'MGTAVTT_6':'(0,0,0,0,C8)';$S;
    'VCCADC_0':'(0,0,0,0,K10)';$S;
    'VCCAUX_1':'(0,0,0,0,H12)';$S;
    'VCCAUX_2':'(0,0,0,0,K12)';$S;
    'VCCAUX_3':'(0,0,0,0,M12)';$S;
    'VCCAUX_4':'(0,0,0,0,P12)';$S;
    'VCCAUX_5':'(0,0,0,0,R11)';$S;
    'VCCBATT_0':'(0,0,0,0,E12)';$S;
    'VCCBRAM_1':'(0,0,0,0,J11)';$S;
    'VCCBRAM_2':'(0,0,0,0,L11)';$S;
    'VCCBRAM_3':'(0,0,0,0,N11)';$S;
    'VCCINT_1':'(0,0,0,0,H10)';$S;
    'VCCINT_2':'(0,0,0,0,H8)';$S;
    'VCCINT_3':'(0,0,0,0,J7)';$S;
    'VCCINT_4':'(0,0,0,0,J9)';$S;
    'VCCINT_5':'(0,0,0,0,K8)';$S;
    'VCCINT_6':'(0,0,0,0,L7)';$S;
    'VCCINT_7':'(0,0,0,0,M8)';$S;
    'VCCINT_8':'(0,0,0,0,N7)';$S;
    'VCCINT_9':'(0,0,0,0,P10)';$S;
    'VCCINT_10':'(0,0,0,0,P8)';$S;
    'VCCINT_11':'(0,0,0,0,R7)';$S;
    'VCCINT_12':'(0,0,0,0,R9)';$S;
    'VCCINT_13':'(0,0,0,0,T10)';$S;
    'VCCINT_14':'(0,0,0,0,T8)';$S;
    'VCCO_0_1':'(0,0,0,0,F12)';$S;
    'VCCO_0_2':'(0,0,0,0,T12)';$S;
    'VCCO_13_1':'(0,0,0,0,AA17)';$S;
    'VCCO_13_2':'(0,0,0,0,AB14)';$S;
    'VCCO_13_3':'(0,0,0,0,V16)';$S;
    'VCCO_13_4':'(0,0,0,0,W13)';$S;
    'VCCO_13_5':'(0,0,0,0,Y10)';$S;
    'VCCO_14_1':'(0,0,0,0,M14)';$S;
    'VCCO_14_2':'(0,0,0,0,P18)';$S;
    'VCCO_14_3':'(0,0,0,0,R15)';$S;
    'VCCO_14_4':'(0,0,0,0,T22)';$S;
    'VCCO_14_5':'(0,0,0,0,U19)';$S;
    'VCCO_14_6':'(0,0,0,0,Y20)';$S;
    'VCCO_15_1':'(0,0,0,0,G19)';$S;
    'VCCO_15_2':'(0,0,0,0,H16)';$S;
    'VCCO_15_3':'(0,0,0,0,J13)';$S;
    'VCCO_15_4':'(0,0,0,0,K20)';$S;
    'VCCO_15_5':'(0,0,0,0,L17)';$S;
    'VCCO_15_6':'(0,0,0,0,N21)';$S;
    'VCCO_16_1':'(0,0,0,0,A17)';$S;
    'VCCO_16_2':'(0,0,0,0,B14)';$S;
    'VCCO_16_3':'(0,0,0,0,C21)';$S;
    'VCCO_16_4':'(0,0,0,0,D18)';$S;
    'VCCO_16_5':'(0,0,0,0,E15)';$S;
    'VCCO_16_6':'(0,0,0,0,F22)';$S;
    'VCCO_34_1':'(0,0,0,0,AA7)';$S;
    'VCCO_34_2':'(0,0,0,0,AB4)';$S;
    'VCCO_34_3':'(0,0,0,0,R5)';$S;
    'VCCO_34_4':'(0,0,0,0,T2)';$S;
    'VCCO_34_5':'(0,0,0,0,V6)';$S;
    'VCCO_34_6':'(0,0,0,0,W3)';$S;
    'VCCO_35_1':'(0,0,0,0,C1)';$S;
    'VCCO_35_2':'(0,0,0,0,F2)';$S;
    'VCCO_35_3':'(0,0,0,0,H6)';$S;
    'VCCO_35_4':'(0,0,0,0,J3)';$S;
    'VCCO_35_5':'(0,0,0,0,M4)';$S;
    'VCCO_35_6':'(0,0,0,0,N1)';$S;
end_primitive;
primitive 'XTAL_2-G131-10075-01';body 'XTAL_2';
    '1':'(1)';
    '2':'(2)';
end_primitive;
primitive 'XTAL_4-G131-10038-02';body 'XTAL_4';
    '1':'(1)';
    '2':'(2)';
    '3':'(3)';
    '4':'(4)';
end_primitive;
END.
